# BASEBOARD_FAB2 (Tioga Pass) — schematic netlist excerpt (pin names and nets, part order shuffled) for the footprints in the layout excerpt that follows; sources: Cadence DE-HDL packaged netlist, KiCad conversion of Wiwynn_Tioga_Pass_MB.brd

EU1A2  IR354XX  IR35411 IC  pkg SM  page 227
  VOS  = PVDDQ_KLM
  LGND  = GND
  VCC  = VR_PVDDQ_KLM_PH1_VCIN
  VDRV  = P5V_STBY
  PGND(0)  = GND
  GL(0)  = TP_PVDDQ_KLM_PH1_GL_0
  PGND(1)  = GND
  SW  = VR_PVDDQ_KLM_PH1_SW
  VIN(0)  = VR_FET_SW_P12V_STBY_PVDDQ_KLM
  VIN(1)  = VR_FET_SW_P12V_STBY_PVDDQ_KLM
  NC  = NC
  PHASE  = VR_PVDDQ_KLM_PH1_PHASE
  BOOST  = VR_PVDDQ_KLM_PH1_BOOT_R
  PWM  = VR_PVDDQ_KLM_PWM1
  EN  = P5V_STBY
  TOUT_FLT  = A_TSENSE_PVDDQ_KLM
  OCSET  = VR_PVDDQ_KLM_PH1_OCSET
  IOUT  = ISENSE_PVDDQ_KLM_PH1_IMON
  REFIN  = VR_PVDDQ_KLM_AIREF1
  PGND(2)  = GND
  GL(1)  = TP_PVDDQ_KLM_PH1_GL_1

(kicad_pcb
	(version 20260206)
	(generator "pcbnew")
	(generator_version "10.0")
	(general
		(thickness 1.6)
		(legacy_teardrops no)
	)
	(paper "A4")
	(title_block
		(title "Wiwynn_Tioga_Pass_MB.brd")
		(comment 1 "Tioga Pass / footprints 317-317 of 4770")
	)
	(layers
		(0 "F.Cu" signal "TOP")
		(4 "In1.Cu" signal "L2GND")
		(6 "In2.Cu" signal "L3")
		(8 "In3.Cu" signal "L4GND")
		(10 "In4.Cu" signal "L5")
		(12 "In5.Cu" signal "L6GND")
		(14 "In6.Cu" signal "L7VCC")
		(16 "In7.Cu" signal "L8VCC")
		(18 "In8.Cu" signal "L9GND")
		(20 "In9.Cu" signal "L10")
		(22 "In10.Cu" signal "L11GND")
		(24 "In11.Cu" signal "L12")
		(26 "In12.Cu" signal "L13GND")
		(2 "B.Cu" signal "BOTTOM")
		(9 "F.Adhes" user "F.Adhesive")
		(11 "B.Adhes" user "B.Adhesive")
		(13 "F.Paste" user "Package Geometry/Pastemask Top")
		(15 "B.Paste" user "Package Geometry/Pastemask Bottom")
		(5 "F.SilkS" user "Ref Des/Silkscreen Top")
		(7 "B.SilkS" user "Ref Des/Silkscreen Bottom")
		(1 "F.Mask" user "Board Geometry/Soldermask Top")
		(3 "B.Mask" user "Board Geometry/Soldermask Bottom")
		(17 "Dwgs.User" user "User.Drawings")
		(19 "Cmts.User" user "User.Comments")
		(21 "Eco1.User" user "User.Eco1")
		(23 "Eco2.User" user "User.Eco2")
		(25 "Edge.Cuts" user "Board Geometry/Outline")
		(27 "Margin" user)
		(31 "F.CrtYd" user "Package Geometry/Place Bound Top")
		(29 "B.CrtYd" user "Package Geometry/Place Bound Bottom")
		(35 "F.Fab" user "Ref Des/Assembly Top")
		(33 "B.Fab" user "Ref Des/Assembly Bottom")
	)
	(footprint ""
		(layer "F.Cu")
		(at 2.397506 -138.184382 90)
		(property "Reference" "EU1A2"
			(at 3.495548 -1.432306 0)
			(unlocked yes)
			(layer "F.SilkS")
			(effects
				(font
					(size 0.7874 0.5842)
					(thickness 0.1524)
				)
			)
		)
		(property "Value" ""
			(at 0 0 90)
			(layer "F.Fab")
			(effects
				(font
					(size 1.27 1.27)
				)
			)
		)
		(duplicate_pad_numbers_are_jumpers no)
		(fp_line
			(start 2.9718 -3.5052)
			(end 2.9718 3.429)
			(stroke
				(width 0.1524)
				(type default)
			)
			(layer "F.SilkS")
		)
		(fp_line
			(start -3.0099 -3.5052)
			(end 2.9718 -3.5052)
			(stroke
				(width 0.1524)
				(type default)
			)
			(layer "F.SilkS")
		)
		(fp_line
			(start 2.9718 3.429)
			(end -3.0099 3.429)
			(stroke
				(width 0.1524)
				(type default)
			)
			(layer "F.SilkS")
		)
		(fp_line
			(start -3.0099 3.429)
			(end -3.0099 -3.5052)
			(stroke
				(width 0.1524)
				(type default)
			)
			(layer "F.SilkS")
		)
		(fp_circle
			(center -3.057398 -2.678684)
			(end -3.057398 -2.551684)
			(stroke
				(width 0.254)
				(type default)
			)
			(fill no)
			(layer "F.SilkS")
		)
		(fp_poly
			(pts
				(xy -2.9972 -3.4925) (xy -2.9972 -2.6924) (xy -2.1971 -3.4925)
			)
			(stroke
				(width 0)
				(type default)
			)
			(fill yes)
			(layer "F.SilkS")
		)
		(fp_poly
			(pts
				(xy -2.549906 -3.050032) (xy -2.549906 3.050032) (xy 2.549906 3.050032) (xy 2.549906 -3.050032)
			)
			(stroke
				(width 0)
				(type default)
			)
			(fill no)
			(layer "F.CrtYd")
		)
		(fp_line
			(start 2.549906 -3.050032)
			(end 2.549906 3.050032)
			(stroke
				(width 0.1)
				(type default)
			)
			(layer "F.Fab")
		)
		(fp_line
			(start -2.549906 -3.050032)
			(end 2.549906 -3.050032)
			(stroke
				(width 0.1)
				(type default)
			)
			(layer "F.Fab")
		)
		(fp_line
			(start 2.549906 3.050032)
			(end -2.549906 3.050032)
			(stroke
				(width 0.1)
				(type default)
			)
			(layer "F.Fab")
		)
		(fp_line
			(start -2.549906 3.050032)
			(end -2.549906 -3.050032)
			(stroke
				(width 0.1)
				(type default)
			)
			(layer "F.Fab")
		)
		(fp_circle
			(center -3.057398 -2.678684)
			(end -3.057398 -2.551684)
			(stroke
				(width 0.254)
				(type default)
			)
			(fill no)
			(layer "F.Fab")
		)
		(pad "1" smd rect
			(at -2.39522 -2.279904 90)
			(size 0.7112 0.254)
			(layers "F.Cu" "F.Mask" "F.Paste")
			(net "PVDDQ_KLM")
		)
		(pad "2" smd rect
			(at -2.39522 -1.83007 90)
			(size 0.7112 0.254)
			(layers "F.Cu" "F.Mask" "F.Paste")
			(net "GND")
		)
		(pad "3" smd rect
			(at -2.39522 -1.379982 90)
			(size 0.7112 0.254)
			(layers "F.Cu" "F.Mask" "F.Paste")
			(net "VR_PVDDQ_KLM_PH1_VCIN")
		)
		(pad "4" smd rect
			(at -2.39522 -0.929894 90)
			(size 0.7112 0.254)
			(layers "F.Cu" "F.Mask" "F.Paste")
			(net "P5V_STBY")
		)
		(pad "5" smd rect
			(at -2.39522 -0.48006 90)
			(size 0.7112 0.254)
			(layers "F.Cu" "F.Mask" "F.Paste")
			(net "GND")
		)
		(pad "6" smd rect
			(at -2.39522 -0.029972 90)
			(size 0.7112 0.254)
			(layers "F.Cu" "F.Mask" "F.Paste")
			(net "TP_PVDDQ_KLM_PH1_GL_0")
		)
		(pad "7" smd custom
			(at 0.016764 1.145032 90)
			(size 0.53975 0.53975)
			(layers "F.Cu" "F.Mask" "F.Paste")
			(net "GND")
			(options
				(clearance outline)
				(anchor circle)
			)
			(primitives
				(gr_poly
					(pts
						(xy -2.7051 1.0795) (xy -2.7051 -0.3683) (xy -0.9271 -0.3683) (xy -0.9271 -1.0795) (xy 2.7051 -1.0795)
						(xy 2.7051 1.0795)
					)
					(width 0)
					(fill yes)
				)
			)
		)
		(pad "10" smd rect
			(at -0.008382 2.874772 90)
			(size 4.3434 0.6096)
			(layers "F.Cu" "F.Mask" "F.Paste")
			(net "VR_PVDDQ_KLM_PH1_SW")
		)
		(pad "25" smd rect
			(at 1.548384 -1.283208 90)
			(size 2.3368 2.0066)
			(layers "F.Cu" "F.Mask" "F.Paste")
			(net "VR_FET_SW_P12V_STBY_PVDDQ_KLM")
		)
		(pad "30" smd rect
			(at 2.050034 -2.895092 90)
			(size 0.254 0.7112)
			(layers "F.Cu" "F.Mask" "F.Paste")
			(net "VR_FET_SW_P12V_STBY_PVDDQ_KLM")
		)
		(pad "31" smd rect
			(at 1.599946 -2.895092 90)
			(size 0.254 0.7112)
			(layers "F.Cu" "F.Mask" "F.Paste")
			(net "Net_372")
		)
		(pad "32" smd rect
			(at 1.150112 -2.895092 90)
			(size 0.254 0.7112)
			(layers "F.Cu" "F.Mask" "F.Paste")
			(net "VR_PVDDQ_KLM_PH1_PHASE")
		)
		(pad "33" smd rect
			(at 0.700024 -2.895092 90)
			(size 0.254 0.7112)
			(layers "F.Cu" "F.Mask" "F.Paste")
			(net "VR_PVDDQ_KLM_PH1_BOOT_R")
		)
		(pad "34" smd rect
			(at 0.249936 -2.895092 90)
			(size 0.254 0.7112)
			(layers "F.Cu" "F.Mask" "F.Paste")
			(net "VR_PVDDQ_KLM_PWM1")
		)
		(pad "35" smd rect
			(at -0.199898 -2.895092 90)
			(size 0.254 0.7112)
			(layers "F.Cu" "F.Mask" "F.Paste")
			(net "P5V_STBY")
		)
		(pad "36" smd rect
			(at -0.649986 -2.895092 90)
			(size 0.254 0.7112)
			(layers "F.Cu" "F.Mask" "F.Paste")
			(net "A_TSENSE_PVDDQ_KLM")
		)
		(pad "37" smd rect
			(at -1.100074 -2.895092 90)
			(size 0.254 0.7112)
			(layers "F.Cu" "F.Mask" "F.Paste")
			(net "VR_PVDDQ_KLM_PH1_OCSET")
		)
		(pad "38" smd rect
			(at -1.549908 -2.895092 90)
			(size 0.254 0.7112)
			(layers "F.Cu" "F.Mask" "F.Paste")
			(net "ISENSE_PVDDQ_KLM_PH1_IMON")
		)
		(pad "39" smd rect
			(at -1.999996 -2.895092 90)
			(size 0.254 0.7112)
			(layers "F.Cu" "F.Mask" "F.Paste")
			(net "VR_PVDDQ_KLM_AIREF1")
		)
		(pad "40" smd rect
			(at -0.871728 -1.283208 90)
			(size 1.8034 2.0066)
			(layers "F.Cu" "F.Mask" "F.Paste")
			(net "GND")
		)
		(pad "41" smd rect
			(at -1.533906 0.247904 90)
			(size 0.508 0.3556)
			(layers "F.Cu" "F.Mask" "F.Paste")
			(net "TP_PVDDQ_KLM_PH1_GL_1")
		)
	)
)
